# BASEBOARD_FAB2 (Tioga Pass) — schematic netlist excerpt (pin names and nets, part order shuffled) for the footprints in the layout excerpt that follows; sources: Cadence DE-HDL packaged netlist, KiCad conversion of Wiwynn_Tioga_Pass_MB.brd

R9F32  RES  10.0K 1% CHIP  pkg 0402  page 239 : A = VR_P1V2_BMC_STBY_FB ; B = GND
CT50  CAP  1000PF 50V 10% X7R  pkg 0402LF  page 216 : A = VR_PVDDQ_ABC_PH1_SW ; B = VR_PVDDQ_ABC_PH1_SW_RC
C1E21  CAP  10UF 16V 10% X6S  pkg 0805  page 161 : A = P12V_FAN ; B = GND

(kicad_pcb
	(version 20260206)
	(generator "pcbnew")
	(generator_version "10.0")
	(general
		(thickness 1.6)
		(legacy_teardrops no)
	)
	(paper "A4")
	(title_block
		(title "Wiwynn_Tioga_Pass_MB.brd")
		(comment 1 "Tioga Pass / footprints 1499-1501 of 4770")
	)
	(layers
		(0 "F.Cu" signal "TOP")
		(4 "In1.Cu" signal "L2GND")
		(6 "In2.Cu" signal "L3")
		(8 "In3.Cu" signal "L4GND")
		(10 "In4.Cu" signal "L5")
		(12 "In5.Cu" signal "L6GND")
		(14 "In6.Cu" signal "L7VCC")
		(16 "In7.Cu" signal "L8VCC")
		(18 "In8.Cu" signal "L9GND")
		(20 "In9.Cu" signal "L10")
		(22 "In10.Cu" signal "L11GND")
		(24 "In11.Cu" signal "L12")
		(26 "In12.Cu" signal "L13GND")
		(2 "B.Cu" signal "BOTTOM")
		(9 "F.Adhes" user "F.Adhesive")
		(11 "B.Adhes" user "B.Adhesive")
		(13 "F.Paste" user "Package Geometry/Pastemask Top")
		(15 "B.Paste" user "Package Geometry/Pastemask Bottom")
		(5 "F.SilkS" user "Ref Des/Silkscreen Top")
		(7 "B.SilkS" user "Ref Des/Silkscreen Bottom")
		(1 "F.Mask" user "Board Geometry/Soldermask Top")
		(3 "B.Mask" user "Board Geometry/Soldermask Bottom")
		(17 "Dwgs.User" user "User.Drawings")
		(19 "Cmts.User" user "User.Comments")
		(21 "Eco1.User" user "User.Eco1")
		(23 "Eco2.User" user "User.Eco2")
		(25 "Edge.Cuts" user "Board Geometry/Outline")
		(27 "Margin" user)
		(31 "F.CrtYd" user "Package Geometry/Place Bound Top")
		(29 "B.CrtYd" user "Package Geometry/Place Bound Bottom")
		(35 "F.Fab" user "Ref Des/Assembly Top")
		(33 "B.Fab" user "Ref Des/Assembly Bottom")
	)
	(footprint ""
		(layer "F.Cu")
		(at 472.227402 -36.880292)
		(property "Reference" "R9F32"
			(at 0 0 0)
			(layer "F.SilkS")
			(hide yes)
			(effects
				(font
					(size 1.27 1.27)
				)
			)
		)
		(property "Value" ""
			(at 0 0 0)
			(layer "F.Fab")
			(effects
				(font
					(size 1.27 1.27)
				)
			)
		)
		(duplicate_pad_numbers_are_jumpers no)
		(fp_poly
			(pts
				(xy -0.2794 -0.1016) (xy 0.2794 -0.1016) (xy 0.2794 0.9906) (xy -0.2794 0.9906)
			)
			(stroke
				(width 0)
				(type default)
			)
			(fill no)
			(layer "F.CrtYd")
		)
		(fp_line
			(start -0.2794 -0.1016)
			(end -0.2794 0.9906)
			(stroke
				(width 0.1)
				(type default)
			)
			(layer "F.Fab")
		)
		(fp_line
			(start -0.2794 0.9906)
			(end 0.2794 0.9906)
			(stroke
				(width 0.1)
				(type default)
			)
			(layer "F.Fab")
		)
		(fp_line
			(start 0.2794 -0.1016)
			(end -0.2794 -0.1016)
			(stroke
				(width 0.1)
				(type default)
			)
			(layer "F.Fab")
		)
		(fp_line
			(start 0.2794 0.9906)
			(end 0.2794 -0.1016)
			(stroke
				(width 0.1)
				(type default)
			)
			(layer "F.Fab")
		)
		(pad "1" smd rect
			(at 0 0)
			(size 0.508 0.508)
			(layers "F.Cu" "F.Mask" "F.Paste")
			(net "VR_P1V2_BMC_STBY_FB")
		)
		(pad "2" smd rect
			(at 0 0.889)
			(size 0.508 0.508)
			(layers "F.Cu" "F.Mask" "F.Paste")
			(net "GND")
		)
		(zone
			(layer "F.Cu")
			(hatch none 0.5)
			(connect_pads
				(clearance 0)
			)
			(min_thickness 0.25)
			(keepout
				(tracks allowed)
				(vias not_allowed)
				(pads allowed)
				(copperpour not_allowed)
				(footprints allowed)
			)
			(placement
				(enabled no)
				(sheetname "")
			)
			(fill
				(thermal_gap 0.5)
				(thermal_bridge_width 0.5)
				(island_removal_mode 0)
			)
			(polygon
				(pts
					(xy 471.973402 -36.626292) (xy 472.481402 -36.626292) (xy 472.481402 -36.245292) (xy 471.973402 -36.245292)
				)
			)
		)
		(zone
			(layer "F.Cu")
			(hatch none 0.5)
			(connect_pads
				(clearance 0)
			)
			(min_thickness 0.25)
			(keepout
				(tracks not_allowed)
				(vias allowed)
				(pads allowed)
				(copperpour not_allowed)
				(footprints allowed)
			)
			(placement
				(enabled no)
				(sheetname "")
			)
			(fill
				(thermal_gap 0.5)
				(thermal_bridge_width 0.5)
				(island_removal_mode 0)
			)
			(polygon
				(pts
					(xy 471.973402 -36.245292) (xy 472.481402 -36.245292) (xy 472.481402 -36.626292) (xy 471.973402 -36.626292)
				)
			)
		)
	)
	(footprint ""
		(layer "F.Cu")
		(at 337.82 -10.3378 90)
		(property "Reference" "CT50"
			(at -0.8382 -0.67818 90)
			(unlocked yes)
			(layer "F.SilkS")
			(effects
				(font
					(size 0.4064 0.254)
					(thickness 0.1524)
				)
				(justify left)
			)
		)
		(property "Value" ""
			(at 0 0 90)
			(layer "F.Fab")
			(effects
				(font
					(size 1.27 1.27)
				)
			)
		)
		(duplicate_pad_numbers_are_jumpers no)
		(fp_poly
			(pts
				(xy 0.3048 -0.1016) (xy 0.3048 0.9906) (xy -0.3048 0.9906) (xy -0.3048 -0.1016)
			)
			(stroke
				(width 0)
				(type default)
			)
			(fill no)
			(layer "F.CrtYd")
		)
		(fp_line
			(start 0.3048 -0.1016)
			(end -0.3048 -0.1016)
			(stroke
				(width 0.1)
				(type default)
			)
			(layer "F.Fab")
		)
		(fp_line
			(start -0.3048 -0.1016)
			(end -0.3048 0.9906)
			(stroke
				(width 0.1)
				(type default)
			)
			(layer "F.Fab")
		)
		(fp_line
			(start 0.3048 0.9906)
			(end 0.3048 -0.1016)
			(stroke
				(width 0.1)
				(type default)
			)
			(layer "F.Fab")
		)
		(fp_line
			(start -0.3048 0.9906)
			(end 0.3048 0.9906)
			(stroke
				(width 0.1)
				(type default)
			)
			(layer "F.Fab")
		)
		(pad "1" smd rect
			(at 0 0 90)
			(size 0.508 0.508)
			(layers "F.Cu" "F.Mask" "F.Paste")
			(net "VR_PVDDQ_ABC_PH1_SW")
		)
		(pad "2" smd rect
			(at 0 0.889 90)
			(size 0.508 0.508)
			(layers "F.Cu" "F.Mask" "F.Paste")
			(net "VR_PVDDQ_ABC_PH1_SW_RC")
		)
		(zone
			(layer "F.Cu")
			(hatch none 0.5)
			(connect_pads
				(clearance 0)
			)
			(min_thickness 0.25)
			(keepout
				(tracks allowed)
				(vias not_allowed)
				(pads allowed)
				(copperpour not_allowed)
				(footprints allowed)
			)
			(placement
				(enabled no)
				(sheetname "")
			)
			(fill
				(thermal_gap 0.5)
				(thermal_bridge_width 0.5)
				(island_removal_mode 0)
			)
			(polygon
				(pts
					(xy 338.074 -10.0838) (xy 338.074 -10.5918) (xy 338.455 -10.5918) (xy 338.455 -10.0838)
				)
			)
		)
		(zone
			(layer "F.Cu")
			(hatch none 0.5)
			(connect_pads
				(clearance 0)
			)
			(min_thickness 0.25)
			(keepout
				(tracks not_allowed)
				(vias allowed)
				(pads allowed)
				(copperpour not_allowed)
				(footprints allowed)
			)
			(placement
				(enabled no)
				(sheetname "")
			)
			(fill
				(thermal_gap 0.5)
				(thermal_bridge_width 0.5)
				(island_removal_mode 0)
			)
			(polygon
				(pts
					(xy 338.455 -10.0838) (xy 338.455 -10.5918) (xy 338.074 -10.5918) (xy 338.074 -10.0838)
				)
			)
		)
	)
	(footprint ""
		(layer "F.Cu")
		(at 28.6004 -41.4782 180)
		(property "Reference" "C1E21"
			(at 0 0 180)
			(layer "F.SilkS")
			(hide yes)
			(effects
				(font
					(size 1.27 1.27)
				)
			)
		)
		(property "Value" ""
			(at 0 0 180)
			(layer "F.Fab")
			(effects
				(font
					(size 1.27 1.27)
				)
			)
		)
		(duplicate_pad_numbers_are_jumpers no)
		(fp_rect
			(start 0.7239 -0.2159)
			(end -0.7239 1.9939)
			(stroke
				(width 0)
				(type default)
			)
			(fill no)
			(layer "F.CrtYd")
		)
		(fp_line
			(start 0.7239 1.9939)
			(end 0.7239 -0.2159)
			(stroke
				(width 0.1)
				(type default)
			)
			(layer "F.Fab")
		)
		(fp_line
			(start 0.7239 -0.2159)
			(end -0.7239 -0.2159)
			(stroke
				(width 0.1)
				(type default)
			)
			(layer "F.Fab")
		)
		(fp_line
			(start -0.7239 1.9939)
			(end 0.7239 1.9939)
			(stroke
				(width 0.1)
				(type default)
			)
			(layer "F.Fab")
		)
		(fp_line
			(start -0.7239 -0.2159)
			(end -0.7239 1.9939)
			(stroke
				(width 0.1)
				(type default)
			)
			(layer "F.Fab")
		)
		(pad "1" smd rect
			(at 0 0 180)
			(size 1.27 1.016)
			(layers "F.Cu" "F.Mask" "F.Paste")
			(net "P12V_FAN")
		)
		(pad "2" smd rect
			(at 0 1.778 180)
			(size 1.27 1.016)
			(layers "F.Cu" "F.Mask" "F.Paste")
			(net "GND")
		)
		(zone
			(layer "F.Cu")
			(hatch none 0.5)
			(connect_pads
				(clearance 0)
			)
			(min_thickness 0.25)
			(keepout
				(tracks not_allowed)
				(vias allowed)
				(pads allowed)
				(copperpour not_allowed)
				(footprints allowed)
			)
			(placement
				(enabled no)
				(sheetname "")
			)
			(fill
				(thermal_gap 0.5)
				(thermal_bridge_width 0.5)
				(island_removal_mode 0)
			)
			(polygon
				(pts
					(xy 27.9654 -41.9862) (xy 29.2354 -41.9862) (xy 29.2354 -42.7482) (xy 27.9654 -42.7482)
				)
			)
		)
	)
)
